(kicad_pcb
	(version 20260206)
	(generator "pcbnew")
	(generator_version "10.0")
	(general
		(thickness 1.6)
		(legacy_teardrops no)
	)
	(paper "A4")
	(title_block
		(title "Bryce Canyon_R.DPB_16317-1_OCP.brd")
		(comment 1 "Bryce Canyon / footprints 1914-1916 of 2099")
	)
	(layers
		(0 "F.Cu" signal "TOP")
		(4 "In1.Cu" signal "L2GND")
		(6 "In2.Cu" signal "L3")
		(8 "In3.Cu" signal "L4VCC")
		(10 "In4.Cu" signal "L5VCC")
		(12 "In5.Cu" signal "L6")
		(14 "In6.Cu" signal "L7GND")
		(2 "B.Cu" signal "BOTTOM")
		(9 "F.Adhes" user "F.Adhesive")
		(11 "B.Adhes" user "B.Adhesive")
		(13 "F.Paste" user "Package Geometry/Pastemask Top")
		(15 "B.Paste" user "Package Geometry/Pastemask Bottom")
		(5 "F.SilkS" user "Ref Des/Silkscreen Top")
		(7 "B.SilkS" user "Ref Des/Silkscreen Bottom")
		(1 "F.Mask" user "Board Geometry/Soldermask Top")
		(3 "B.Mask" user "Board Geometry/Soldermask Bottom")
		(17 "Dwgs.User" user "User.Drawings")
		(19 "Cmts.User" user "User.Comments")
		(21 "Eco1.User" user "User.Eco1")
		(23 "Eco2.User" user "User.Eco2")
		(25 "Edge.Cuts" user "Board Geometry/Outline")
		(27 "Margin" user)
		(31 "F.CrtYd" user "Package Geometry/Place Bound Top")
		(29 "B.CrtYd" user "Package Geometry/Place Bound Bottom")
		(35 "F.Fab" user "Ref Des/Assembly Top")
		(33 "B.Fab" user "Ref Des/Assembly Bottom")
	)
	(footprint ""
		(layer "F.Cu")
		(at 388.649972 -258.910074 -90)
		(property "Reference" "HDDSAS8"
			(at 0 0 270)
			(layer "F.SilkS")
			(hide yes)
			(effects
				(font
					(size 1.27 1.27)
				)
			)
		)
		(property "Value" "SKT-SAS15P-14P-45-GP"
			(at -20.7645 -8.9789 270)
			(unlocked yes)
			(layer "F.Fab")
			(hide yes)
			(effects
				(font
					(size 1.016 1.016)
					(thickness 0.1524)
				)
			)
		)
		(property "Device Type" "10120818-001C-TRLF"
			(at -20.7645 -10.5029 270)
			(unlocked yes)
			(layer "F.Fab")
			(hide yes)
			(effects
				(font
					(size 1.016 1.016)
					(thickness 0.1524)
				)
			)
		)
		(duplicate_pad_numbers_are_jumpers no)
		(fp_line
			(start 1.651 4.2926)
			(end 1.651 3.0099)
			(stroke
				(width 0.1524)
				(type default)
			)
			(layer "F.SilkS")
		)
		(fp_line
			(start 8.509 4.2926)
			(end 1.651 4.2926)
			(stroke
				(width 0.1524)
				(type default)
			)
			(layer "F.SilkS")
		)
		(fp_line
			(start -23.4188 3.0099)
			(end -23.4188 -3.2512)
			(stroke
				(width 0.1524)
				(type default)
			)
			(layer "F.SilkS")
		)
		(fp_line
			(start 1.651 3.0099)
			(end -23.4188 3.0099)
			(stroke
				(width 0.1524)
				(type default)
			)
			(layer "F.SilkS")
		)
		(fp_line
			(start 8.509 3.0099)
			(end 8.509 4.2926)
			(stroke
				(width 0.1524)
				(type default)
			)
			(layer "F.SilkS")
		)
		(fp_line
			(start 23.4188 3.0099)
			(end 8.509 3.0099)
			(stroke
				(width 0.1524)
				(type default)
			)
			(layer "F.SilkS")
		)
		(fp_line
			(start -23.4188 -3.2512)
			(end 23.4188 -3.2512)
			(stroke
				(width 0.1524)
				(type default)
			)
			(layer "F.SilkS")
		)
		(fp_line
			(start 23.4188 -3.2512)
			(end 23.4188 3.0099)
			(stroke
				(width 0.1524)
				(type default)
			)
			(layer "F.SilkS")
		)
		(fp_line
			(start 15.5067 -3.3401)
			(end 16.2687 -3.3401)
			(stroke
				(width 0.3302)
				(type default)
			)
			(layer "F.SilkS")
		)
		(fp_poly
			(pts
				(xy 15.868904 -3.230372) (xy 16.503904 -3.865372) (xy 15.233904 -3.865372)
			)
			(stroke
				(width 0)
				(type default)
			)
			(fill yes)
			(layer "F.SilkS")
		)
		(fp_poly
			(pts
				(xy -22.8727 -2.7559) (xy 22.8727 -2.7559) (xy 22.8727 2.7559) (xy 8.255 2.7559) (xy 8.255 3.5179)
				(xy 1.905 3.5179) (xy 1.905 2.7559) (xy -22.8727 2.7559)
			)
			(stroke
				(width 0)
				(type default)
			)
			(fill no)
			(layer "F.CrtYd")
		)
		(fp_poly
			(pts
				(xy 1.397 4.5466) (xy 1.397 3.2639) (xy -23.6728 3.2639) (xy -23.6728 -3.5052) (xy 23.6728 -3.5052)
				(xy 23.6728 -0.00635) (xy 22.8727 -0.00635) (xy 22.8727 -2.7559) (xy -22.8727 -2.7559) (xy -22.8727 2.7559)
				(xy 1.905 2.7559) (xy 1.905 3.5179) (xy 8.255 3.5179) (xy 8.255 2.7559) (xy 22.8727 2.7559) (xy 22.8727 0.00635)
				(xy 23.6728 0.00635) (xy 23.6728 3.2639) (xy 8.763 3.2639) (xy 8.763 4.5466)
			)
			(stroke
				(width 0)
				(type default)
			)
			(fill no)
			(layer "F.CrtYd")
		)
		(fp_poly
			(pts
				(xy 1.397 4.5466) (xy 1.397 3.2639) (xy -23.6728 3.2639) (xy -23.6728 -3.5052) (xy 23.6728 -3.5052)
				(xy 23.6728 3.2639) (xy 8.763 3.2639) (xy 8.763 4.5466)
			)
			(stroke
				(width 0)
				(type default)
			)
			(fill no)
			(layer "F.Fab")
		)
		(pad "" np_thru_hole circle
			(at -18.874994 0 270)
			(size 0.254 0.254)
			(drill 1.3462)
			(layers "*.Cu" "*.Mask")
			(clearance 0.9017)
			(thermal_gap 0.9017)
		)
		(pad "" np_thru_hole circle
			(at 18.874994 0 270)
			(size 0.254 0.254)
			(drill 0.9398)
			(layers "*.Cu" "*.Mask")
			(clearance 0.6985)
			(thermal_gap 0.6985)
		)
		(pad "G1" smd rect
			(at 21.874988 0 270)
			(size 2.5908 2.5908)
			(layers "F.Cu" "F.Mask" "F.Paste")
			(net "GND")
		)
		(pad "G2" smd rect
			(at -21.874988 0 270)
			(size 2.5908 2.5908)
			(layers "F.Cu" "F.Mask" "F.Paste")
			(net "GND")
		)
		(pad "P1" smd rect
			(at 1.905 -1.82499 270)
			(size 0.6096 2.3622)
			(layers "F.Cu" "F.Mask" "F.Paste")
			(net "Net_1589")
		)
		(pad "P2" smd rect
			(at 0.635 -1.82499 270)
			(size 0.6096 2.3622)
			(layers "F.Cu" "F.Mask" "F.Paste")
			(net "Net_1590")
		)
		(pad "P3" smd rect
			(at -0.635 -1.82499 270)
			(size 0.6096 2.3622)
			(layers "F.Cu" "F.Mask" "F.Paste")
			(net "Net_1591")
		)
		(pad "P4" smd rect
			(at -1.905 -1.82499 270)
			(size 0.6096 2.3622)
			(layers "F.Cu" "F.Mask" "F.Paste")
			(net "GND")
		)
		(pad "P5" smd rect
			(at -3.175 -1.82499 270)
			(size 0.6096 2.3622)
			(layers "F.Cu" "F.Mask" "F.Paste")
			(net "HDD_PRSNT_8")
		)
		(pad "P6" smd rect
			(at -4.445 -1.82499 270)
			(size 0.6096 2.3622)
			(layers "F.Cu" "F.Mask" "F.Paste")
			(net "GND")
		)
		(pad "P7" smd rect
			(at -5.715 -1.82499 270)
			(size 0.6096 2.3622)
			(layers "F.Cu" "F.Mask" "F.Paste")
			(net "5V_PRE_8")
		)
		(pad "P8" smd rect
			(at -6.985 -1.82499 270)
			(size 0.6096 2.3622)
			(layers "F.Cu" "F.Mask" "F.Paste")
			(net "P5V_HDD8")
		)
		(pad "P9" smd rect
			(at -8.255 -1.82499 270)
			(size 0.6096 2.3622)
			(layers "F.Cu" "F.Mask" "F.Paste")
			(net "P5V_HDD8")
		)
		(pad "P10" smd rect
			(at -9.525 -1.82499 270)
			(size 0.6096 2.3622)
			(layers "F.Cu" "F.Mask" "F.Paste")
			(net "GND")
		)
		(pad "P11" smd rect
			(at -10.795 -1.82499 270)
			(size 0.6096 2.3622)
			(layers "F.Cu" "F.Mask" "F.Paste")
			(net "ACT_HDD_8")
		)
		(pad "P12" smd rect
			(at -12.065 -1.82499 270)
			(size 0.6096 2.3622)
			(layers "F.Cu" "F.Mask" "F.Paste")
			(net "GND")
		)
		(pad "P13" smd rect
			(at -13.335 -1.82499 270)
			(size 0.6096 2.3622)
			(layers "F.Cu" "F.Mask" "F.Paste")
			(net "12V_PRE_8")
		)
		(pad "P14" smd rect
			(at -14.605 -1.82499 270)
			(size 0.6096 2.3622)
			(layers "F.Cu" "F.Mask" "F.Paste")
			(net "P12V_HDD8")
		)
		(pad "P15" smd rect
			(at -15.875 -1.82499 270)
			(size 0.6096 2.3622)
			(layers "F.Cu" "F.Mask" "F.Paste")
			(net "P12V_HDD8")
		)
		(pad "S1" smd rect
			(at 15.875 -1.82499 270)
			(size 0.6096 2.3622)
			(layers "F.Cu" "F.Mask" "F.Paste")
			(net "GND")
		)
		(pad "S2" smd rect
			(at 14.605 -1.82499 270)
			(size 0.6096 2.3622)
			(layers "F.Cu" "F.Mask" "F.Paste")
			(net "SAS_HDD_RX_P8")
		)
		(pad "S3" smd rect
			(at 13.335 -1.82499 270)
			(size 0.6096 2.3622)
			(layers "F.Cu" "F.Mask" "F.Paste")
			(net "SAS_HDD_RX_N8")
		)
		(pad "S4" smd rect
			(at 12.065 -1.82499 270)
			(size 0.6096 2.3622)
			(layers "F.Cu" "F.Mask" "F.Paste")
			(net "GND")
		)
		(pad "S5" smd rect
			(at 10.795 -1.82499 270)
			(size 0.6096 2.3622)
			(layers "F.Cu" "F.Mask" "F.Paste")
			(net "PHY_DRV_B_TO_SCC_B_8_DN")
		)
		(pad "S6" smd rect
			(at 9.525 -1.82499 270)
			(size 0.6096 2.3622)
			(layers "F.Cu" "F.Mask" "F.Paste")
			(net "PHY_DRV_B_TO_SCC_B_8_DP")
		)
		(pad "S7" smd rect
			(at 8.255 -1.82499 270)
			(size 0.6096 2.3622)
			(layers "F.Cu" "F.Mask" "F.Paste")
			(net "GND")
		)
		(pad "S8" smd rect
			(at 7.480046 2.845054 270)
			(size 0.508 2.3622)
			(layers "F.Cu" "F.Mask" "F.Paste")
			(net "GND")
		)
		(pad "S9" smd rect
			(at 6.679946 2.845054 270)
			(size 0.508 2.3622)
			(layers "F.Cu" "F.Mask" "F.Paste")
			(net "Net_466")
		)
		(pad "S10" smd rect
			(at 5.8801 2.845054 270)
			(size 0.508 2.3622)
			(layers "F.Cu" "F.Mask" "F.Paste")
			(net "Net_358")
		)
		(pad "S11" smd rect
			(at 5.08 2.845054 270)
			(size 0.508 2.3622)
			(layers "F.Cu" "F.Mask" "F.Paste")
			(net "GND")
		)
		(pad "S12" smd rect
			(at 4.2799 2.845054 270)
			(size 0.508 2.3622)
			(layers "F.Cu" "F.Mask" "F.Paste")
			(net "Net_394")
		)
		(pad "S13" smd rect
			(at 3.480054 2.845054 270)
			(size 0.508 2.3622)
			(layers "F.Cu" "F.Mask" "F.Paste")
			(net "Net_430")
		)
		(pad "S14" smd rect
			(at 2.679954 2.845054 270)
			(size 0.508 2.3622)
			(layers "F.Cu" "F.Mask" "F.Paste")
			(net "GND")
		)
		(zone
			(layer "F.Cu")
			(hatch none 0.5)
			(connect_pads
				(clearance 0)
			)
			(min_thickness 0.25)
			(keepout
				(tracks allowed)
				(vias not_allowed)
				(pads allowed)
				(copperpour not_allowed)
				(footprints allowed)
			)
			(placement
				(enabled no)
				(sheetname "")
			)
			(fill
				(thermal_gap 0.5)
				(thermal_bridge_width 0.5)
				(island_removal_mode 0)
			)
			(polygon
				(pts
					(xy 392.307572 -275.648674) (xy 385.233672 -275.648674) (xy 385.233672 -282.582874) (xy 386.338572 -282.582874)
					(xy 386.338572 -278.468074) (xy 390.961372 -278.468074) (xy 390.961372 -282.582874) (xy 392.307572 -282.582874)
				)
			)
		)
		(zone
			(layer "F.Cu")
			(hatch none 0.5)
			(connect_pads
				(clearance 0)
			)
			(min_thickness 0.25)
			(keepout
				(tracks not_allowed)
				(vias allowed)
				(pads allowed)
				(copperpour not_allowed)
				(footprints allowed)
			)
			(placement
				(enabled no)
				(sheetname "")
			)
			(fill
				(thermal_gap 0.5)
				(thermal_bridge_width 0.5)
				(island_removal_mode 0)
			)
			(polygon
				(pts
					(xy 392.307572 -275.648674) (xy 385.233672 -275.648674) (xy 385.233672 -282.582874) (xy 386.338572 -282.582874)
					(xy 386.338572 -278.468074) (xy 390.961372 -278.468074) (xy 390.961372 -282.582874) (xy 392.307572 -282.582874)
				)
			)
		)
		(zone
			(layer "F.Cu")
			(hatch none 0.5)
			(connect_pads
				(clearance 0)
			)
			(min_thickness 0.25)
			(keepout
				(tracks not_allowed)
				(vias allowed)
				(pads allowed)
				(copperpour not_allowed)
				(footprints allowed)
			)
			(placement
				(enabled no)
				(sheetname "")
			)
			(fill
				(thermal_gap 0.5)
				(thermal_bridge_width 0.5)
				(island_removal_mode 0)
			)
			(polygon
				(pts
					(xy 392.307572 -242.171474) (xy 385.233672 -242.171474) (xy 385.233672 -235.237274) (xy 386.338572 -235.237274)
					(xy 386.338572 -239.352074) (xy 390.961372 -239.352074) (xy 390.961372 -235.237274) (xy 392.307572 -235.237274)
				)
			)
		)
		(zone
			(layer "F.Cu")
			(hatch none 0.5)
			(connect_pads
				(clearance 0)
			)
			(min_thickness 0.25)
			(keepout
				(tracks allowed)
				(vias not_allowed)
				(pads allowed)
				(copperpour not_allowed)
				(footprints allowed)
			)
			(placement
				(enabled no)
				(sheetname "")
			)
			(fill
				(thermal_gap 0.5)
				(thermal_bridge_width 0.5)
				(island_removal_mode 0)
			)
			(polygon
				(pts
					(xy 392.307572 -242.171474) (xy 385.233672 -242.171474) (xy 385.233672 -235.237274) (xy 386.338572 -235.237274)
					(xy 386.338572 -239.352074) (xy 390.961372 -239.352074) (xy 390.961372 -235.237274) (xy 392.307572 -235.237274)
				)
			)
		)
		(zone
			(layers "F.Cu" "B.Cu" "In1.Cu" "In2.Cu" "In3.Cu" "In4.Cu" "In5.Cu" "In6.Cu")
			(hatch none 0.5)
			(connect_pads
				(clearance 0)
			)
			(min_thickness 0.25)
			(keepout
				(tracks not_allowed)
				(vias allowed)
				(pads allowed)
				(copperpour not_allowed)
				(footprints allowed)
			)
			(placement
				(enabled no)
				(sheetname "")
			)
			(fill
				(thermal_gap 0.5)
				(thermal_bridge_width 0.5)
				(island_removal_mode 0)
			)
			(polygon
				(pts
					(arc
						(start 389.424672 -240.03508)
						(mid 387.875272 -240.03508)
						(end 389.424672 -240.03508)
					)
				)
			)
		)
		(zone
			(layers "F.Cu" "B.Cu" "In1.Cu" "In2.Cu" "In3.Cu" "In4.Cu" "In5.Cu" "In6.Cu")
			(hatch none 0.5)
			(connect_pads
				(clearance 0)
			)
			(min_thickness 0.25)
			(keepout
				(tracks not_allowed)
				(vias allowed)
				(pads allowed)
				(copperpour not_allowed)
				(footprints allowed)
			)
			(placement
				(enabled no)
				(sheetname "")
			)
			(fill
				(thermal_gap 0.5)
				(thermal_bridge_width 0.5)
				(island_removal_mode 0)
			)
			(polygon
				(pts
					(arc
						(start 389.627872 -277.785068)
						(mid 387.672072 -277.785068)
						(end 389.627872 -277.785068)
					)
				)
			)
		)
	)
	(footprint ""
		(layer "F.Cu")
		(at 330.67498 -178.799998)
		(property "Reference" ""
			(at 0 0 0)
			(layer "F.SilkS")
			(hide yes)
			(effects
				(font
					(size 1.27 1.27)
				)
			)
		)
		(property "Value" "*"
			(at -8.398764 -8.057642 0)
			(unlocked yes)
			(layer "F.Fab")
			(hide yes)
			(effects
				(font
					(size 1.016 1.016)
					(thickness 0.1524)
				)
			)
		)
		(duplicate_pad_numbers_are_jumpers no)
		(fp_poly
			(pts
				(arc
					(start 7.3152 0)
					(mid 0 7.3152)
					(end -7.3152 0)
				)
				(arc
					(start -7.3152 -5.9944)
					(mid 0 -13.3096)
					(end 7.3152 -5.9944)
				)
			)
			(stroke
				(width 0)
				(type default)
			)
			(fill no)
			(layer "B.CrtYd")
		)
		(fp_poly
			(pts
				(arc
					(start 7.3152 0)
					(mid 0 7.3152)
					(end -7.3152 0)
				)
				(arc
					(start -7.3152 -5.9944)
					(mid 0 -13.3096)
					(end 7.3152 -5.9944)
				)
			)
			(stroke
				(width 0)
				(type default)
			)
			(fill no)
			(layer "F.CrtYd")
		)
		(fp_poly
			(pts
				(arc
					(start 7.3152 0)
					(mid 0 7.3152)
					(end -7.3152 0)
				)
				(arc
					(start -7.3152 -5.9944)
					(mid 0 -13.3096)
					(end 7.3152 -5.9944)
				)
			)
			(stroke
				(width 0)
				(type default)
			)
			(fill no)
			(layer "B.Fab")
		)
		(fp_poly
			(pts
				(arc
					(start 7.3152 0)
					(mid 0 7.3152)
					(end -7.3152 0)
				)
				(arc
					(start -7.3152 -5.9944)
					(mid 0 -13.3096)
					(end 7.3152 -5.9944)
				)
			)
			(stroke
				(width 0)
				(type default)
			)
			(fill no)
			(layer "F.Fab")
		)
		(pad "1" thru_hole oval
			(at 0 0)
			(size 14.0208 20.0152)
			(drill 0.0254
				(offset 0 -2.9972)
			)
			(layers "*.Cu" "*.Mask")
			(remove_unused_layers no)
			(net "Net_44")
			(clearance -1.002284)
			(thermal_gap 0.1524)
			(padstack
				(mode front_inner_back)
				(layer "Inner"
					(shape custom)
					(size 2.928012 2.928012)
					(options
						(anchor circle)
					)
					(primitives
						(gr_poly
							(pts
								(arc
									(start 4.571746 -2.084324)
									(mid 0.000333 7.430372)
									(end -4.571492 -2.084324)
								)
								(arc
									(start -4.571492 -2.084324)
									(mid -3.570296 -3.611977)
									(end -2.875026 -5.30098)
								)
								(arc
									(start -2.875026 -5.30098)
									(mid 0.000217 -7.43089)
									(end 2.87528 -5.30098)
								)
								(arc
									(start 2.87528 -5.30098)
									(mid 3.570511 -3.611956)
									(end 4.571746 -2.084324)
								)
							)
							(width 0)
							(fill yes)
						)
					)
					(clearance 0.1524)
				)
				(layer "B.Cu"
					(shape oval)
					(size 14.0208 20.0152)
					(offset 0 -2.9972)
					(clearance -1.002284)
				)
			)
		)
		(zone
			(layers "F.Cu" "B.Cu" "In1.Cu" "In2.Cu" "In3.Cu" "In4.Cu" "In5.Cu" "In6.Cu")
			(hatch none 0.5)
			(connect_pads
				(clearance 0)
			)
			(min_thickness 0.25)
			(keepout
				(tracks not_allowed)
				(vias allowed)
				(pads allowed)
				(copperpour not_allowed)
				(footprints allowed)
			)
			(placement
				(enabled no)
				(sheetname "")
			)
			(fill
				(thermal_gap 0.5)
				(thermal_bridge_width 0.5)
				(island_removal_mode 0)
			)
			(polygon
				(pts
					(arc
						(start 323.66458 -184.794398)
						(mid 330.67498 -191.804798)
						(end 337.68538 -184.794398)
					)
					(arc
						(start 337.68538 -178.799998)
						(mid 330.67498 -171.789598)
						(end 323.66458 -178.799998)
					)
				)
			)
		)
	)
	(footprint ""
		(layer "F.Cu")
		(at 384.9116 -261.6454)
		(property "Reference" "C141"
			(at 0 0 0)
			(layer "F.SilkS")
			(hide yes)
			(effects
				(font
					(size 1.27 1.27)
				)
			)
		)
		(property "Value" "SCD01U50V2KX-1GP"
			(at 1.1811 -2.7051 0)
			(unlocked yes)
			(layer "F.Fab")
			(hide yes)
			(effects
				(font
					(size 1.016 1.016)
					(thickness 0.1524)
				)
			)
		)
		(property "Device Type" "C402H22"
			(at 1.1811 -4.2291 0)
			(unlocked yes)
			(layer "F.Fab")
			(hide yes)
			(effects
				(font
					(size 1.016 1.016)
					(thickness 0.1524)
				)
			)
		)
		(duplicate_pad_numbers_are_jumpers no)
		(fp_rect
			(start -0.4318 0.9525)
			(end 0.4318 -0.9525)
			(stroke
				(width 0)
				(type default)
			)
			(fill no)
			(layer "F.CrtYd")
		)
		(fp_rect
			(start -0.4318 0.9525)
			(end 0.4318 -0.9525)
			(stroke
				(width 0)
				(type default)
			)
			(fill no)
			(layer "F.Fab")
		)
		(pad "1" smd custom
			(at 0 -0.4445)
			(size 0.1524 0.1524)
			(layers "F.Cu" "F.Mask" "F.Paste")
			(net "HDD_PRSNT_8")
			(options
				(clearance outline)
				(anchor circle)
			)
			(primitives
				(gr_poly
					(pts
						(arc
							(start 0.3048 -0.2032)
							(mid 0.275042 -0.275042)
							(end 0.2032 -0.3048)
						)
						(arc
							(start -0.2032 -0.3048)
							(mid -0.275042 -0.275042)
							(end -0.3048 -0.2032)
						)
						(arc
							(start -0.3048 0.2032)
							(mid -0.275042 0.275042)
							(end -0.2032 0.3048)
						)
						(arc
							(start 0.2032 0.3048)
							(mid 0.275042 0.275042)
							(end 0.3048 0.2032)
						)
					)
					(width 0)
					(fill yes)
				)
			)
		)
		(pad "2" smd custom
			(at 0 0.4445)
			(size 0.1524 0.1524)
			(layers "F.Cu" "F.Mask" "F.Paste")
			(net "GND")
			(options
				(clearance outline)
				(anchor circle)
			)
			(primitives
				(gr_poly
					(pts
						(arc
							(start 0.3048 -0.2032)
							(mid 0.275042 -0.275042)
							(end 0.2032 -0.3048)
						)
						(arc
							(start -0.2032 -0.3048)
							(mid -0.275042 -0.275042)
							(end -0.3048 -0.2032)
						)
						(arc
							(start -0.3048 0.2032)
							(mid -0.275042 0.275042)
							(end -0.2032 0.3048)
						)
						(arc
							(start 0.2032 0.3048)
							(mid 0.275042 0.275042)
							(end 0.3048 0.2032)
						)
					)
					(width 0)
					(fill yes)
				)
			)
		)
	)
)
